(kicad_pcb
	(version 20260206)
	(generator "pcbnew")
	(generator_version "10.0")
	(general
		(thickness 1.6)
		(legacy_teardrops no)
	)
	(paper "A4")
	(title_block
		(title "v1-chassis-manager — T6M_CM_d_v01_1031_1645.brd")
		(comment 1 "Open CloudServer (Microsoft) / footprints 954-962 of 2512")
	)
	(layers
		(0 "F.Cu" signal "TOP")
		(4 "In1.Cu" signal "GND1")
		(6 "In2.Cu" signal "IN1")
		(8 "In3.Cu" signal "VCC1")
		(10 "In4.Cu" signal "VCC2")
		(12 "In5.Cu" signal "GND2")
		(14 "In6.Cu" signal "IN2")
		(16 "In7.Cu" signal "IN3")
		(18 "In8.Cu" signal "GND3")
		(2 "B.Cu" signal "BOTTOM")
		(9 "F.Adhes" user "F.Adhesive")
		(11 "B.Adhes" user "B.Adhesive")
		(13 "F.Paste" user "Package Geometry/Pastemask Top")
		(15 "B.Paste" user "Package Geometry/Pastemask Bottom")
		(5 "F.SilkS" user "Ref Des/Silkscreen Top")
		(7 "B.SilkS" user "Ref Des/Silkscreen Bottom")
		(1 "F.Mask" user "Board Geometry/Soldermask Top")
		(3 "B.Mask" user "Board Geometry/Soldermask Bottom")
		(17 "Dwgs.User" user "User.Drawings")
		(19 "Cmts.User" user "User.Comments")
		(21 "Eco1.User" user "User.Eco1")
		(23 "Eco2.User" user "User.Eco2")
		(25 "Edge.Cuts" user "Board Geometry/Outline")
		(27 "Margin" user)
		(31 "F.CrtYd" user "Package Geometry/Place Bound Top")
		(29 "B.CrtYd" user "Package Geometry/Place Bound Bottom")
		(35 "F.Fab" user "Ref Des/Assembly Top")
		(33 "B.Fab" user "Ref Des/Assembly Bottom")
	)
	(footprint ""
		(layer "F.Cu")
		(at 137.98169 -53.754528 180)
		(property "Reference" "R1156"
			(at 4.53009 -0.212598 0)
			(unlocked yes)
			(layer "F.SilkS")
			(effects
				(font
					(size 0.7874 0.5842)
					(thickness 0.1524)
				)
				(justify left)
			)
		)
		(property "Value" ""
			(at 0 0 180)
			(layer "F.Fab")
			(effects
				(font
					(size 1.27 1.27)
				)
			)
		)
		(duplicate_pad_numbers_are_jumpers no)
		(fp_line
			(start 0.7874 0.4064)
			(end -0.7874 0.4064)
			(stroke
				(width 0.1524)
				(type default)
			)
			(layer "F.SilkS")
		)
		(fp_line
			(start 0.7874 -0.4064)
			(end 0.7874 0.4064)
			(stroke
				(width 0.1524)
				(type default)
			)
			(layer "F.SilkS")
		)
		(fp_line
			(start -0.7874 0.4064)
			(end -0.7874 -0.4064)
			(stroke
				(width 0.1524)
				(type default)
			)
			(layer "F.SilkS")
		)
		(fp_line
			(start -0.7874 -0.4064)
			(end 0.7874 -0.4064)
			(stroke
				(width 0.1524)
				(type default)
			)
			(layer "F.SilkS")
		)
		(fp_poly
			(pts
				(xy -0.508 0.2794) (xy -0.508 0.2286) (xy -0.635 0.2286) (xy -0.635 -0.254) (xy -0.5334 -0.254)
				(xy -0.5334 -0.2794) (xy 0.5334 -0.2794) (xy 0.5334 -0.254) (xy 0.635 -0.254) (xy 0.635 0.254) (xy 0.5334 0.254)
				(xy 0.5334 0.2794)
			)
			(stroke
				(width 0)
				(type default)
			)
			(fill no)
			(layer "F.CrtYd")
		)
		(pad "1" smd rect
			(at 0.40005 0 180)
			(size 0.4572 0.508)
			(layers "F.Cu" "F.Mask" "F.Paste")
			(net "UART_DTR_P3_N")
		)
		(pad "2" smd rect
			(at -0.40005 0 180)
			(size 0.4572 0.508)
			(layers "F.Cu" "F.Mask" "F.Paste")
			(net "GND")
		)
	)
	(footprint ""
		(layer "F.Cu")
		(at 63.10376 -188.126624 90)
		(property "Reference" "C697"
			(at 4.548886 -0.019558 90)
			(unlocked yes)
			(layer "F.SilkS")
			(effects
				(font
					(size 0.7874 0.5842)
					(thickness 0.1524)
				)
				(justify left)
			)
		)
		(property "Value" ""
			(at 0 0 90)
			(layer "F.Fab")
			(effects
				(font
					(size 1.27 1.27)
				)
			)
		)
		(duplicate_pad_numbers_are_jumpers no)
		(fp_line
			(start 0.7874 -0.4064)
			(end 0.7874 0.4064)
			(stroke
				(width 0.1524)
				(type default)
			)
			(layer "F.SilkS")
		)
		(fp_line
			(start -0.7874 -0.4064)
			(end 0.7874 -0.4064)
			(stroke
				(width 0.1524)
				(type default)
			)
			(layer "F.SilkS")
		)
		(fp_line
			(start 0 0.381)
			(end 0 -0.381)
			(stroke
				(width 0.1524)
				(type default)
			)
			(layer "F.SilkS")
		)
		(fp_line
			(start 0.7874 0.4064)
			(end -0.7874 0.4064)
			(stroke
				(width 0.1524)
				(type default)
			)
			(layer "F.SilkS")
		)
		(fp_line
			(start -0.7874 0.4064)
			(end -0.7874 -0.4064)
			(stroke
				(width 0.1524)
				(type default)
			)
			(layer "F.SilkS")
		)
		(fp_poly
			(pts
				(xy -0.5334 0.254) (xy -0.635 0.254) (xy -0.635 0.2286) (xy -0.635 -0.254) (xy -0.5334 -0.254) (xy -0.5334 -0.2794)
				(xy 0.5334 -0.2794) (xy 0.5334 -0.254) (xy 0.635 -0.254) (xy 0.635 0.254) (xy 0.5334 0.254) (xy 0.5334 0.2794)
				(xy -0.508 0.2794) (xy -0.5334 0.2794)
			)
			(stroke
				(width 0)
				(type default)
			)
			(fill no)
			(layer "F.CrtYd")
		)
		(pad "1" smd rect
			(at 0.40005 0 90)
			(size 0.4572 0.508)
			(layers "F.Cu" "F.Mask" "F.Paste")
			(net "UART_T2_NODE1_TXD_R")
		)
		(pad "2" smd rect
			(at -0.40005 0 90)
			(size 0.4572 0.508)
			(layers "F.Cu" "F.Mask" "F.Paste")
			(net "GND")
		)
	)
	(footprint ""
		(layer "F.Cu")
		(at 88.291924 -180.790596 -90)
		(property "Reference" "R1177"
			(at 2.271776 -1.026922 90)
			(unlocked yes)
			(layer "F.SilkS")
			(effects
				(font
					(size 0.635 0.4064)
					(thickness 0.1524)
				)
				(justify left)
			)
		)
		(property "Value" ""
			(at 0 0 270)
			(layer "F.Fab")
			(effects
				(font
					(size 1.27 1.27)
				)
			)
		)
		(duplicate_pad_numbers_are_jumpers no)
		(fp_line
			(start -0.7874 0.4064)
			(end -0.7874 -0.4064)
			(stroke
				(width 0.1524)
				(type default)
			)
			(layer "F.SilkS")
		)
		(fp_line
			(start 0.7874 0.4064)
			(end -0.7874 0.4064)
			(stroke
				(width 0.1524)
				(type default)
			)
			(layer "F.SilkS")
		)
		(fp_line
			(start -0.7874 -0.4064)
			(end 0.7874 -0.4064)
			(stroke
				(width 0.1524)
				(type default)
			)
			(layer "F.SilkS")
		)
		(fp_line
			(start 0.7874 -0.4064)
			(end 0.7874 0.4064)
			(stroke
				(width 0.1524)
				(type default)
			)
			(layer "F.SilkS")
		)
		(fp_poly
			(pts
				(xy -0.508 0.2794) (xy -0.508 0.2286) (xy -0.635 0.2286) (xy -0.635 -0.254) (xy -0.5334 -0.254)
				(xy -0.5334 -0.2794) (xy 0.5334 -0.2794) (xy 0.5334 -0.254) (xy 0.635 -0.254) (xy 0.635 0.254) (xy 0.5334 0.254)
				(xy 0.5334 0.2794)
			)
			(stroke
				(width 0)
				(type default)
			)
			(fill no)
			(layer "F.CrtYd")
		)
		(pad "1" smd rect
			(at 0.40005 0 270)
			(size 0.4572 0.508)
			(layers "F.Cu" "F.Mask" "F.Paste")
			(net "CPLD_UART_DTR_P4_N")
		)
		(pad "2" smd rect
			(at -0.40005 0 270)
			(size 0.4572 0.508)
			(layers "F.Cu" "F.Mask" "F.Paste")
			(net "GND")
		)
	)
	(footprint ""
		(layer "F.Cu")
		(at 55.78856 -121.344182 -90)
		(property "Reference" "R312"
			(at 2.333752 5.8801 90)
			(unlocked yes)
			(layer "F.SilkS")
			(effects
				(font
					(size 0.7874 0.5842)
					(thickness 0.1524)
				)
				(justify left)
			)
		)
		(property "Value" ""
			(at 0 0 270)
			(layer "F.Fab")
			(effects
				(font
					(size 1.27 1.27)
				)
			)
		)
		(duplicate_pad_numbers_are_jumpers no)
		(fp_line
			(start -0.7874 0.4064)
			(end -0.7874 -0.4064)
			(stroke
				(width 0.1524)
				(type default)
			)
			(layer "F.SilkS")
		)
		(fp_line
			(start 0.7874 0.4064)
			(end -0.7874 0.4064)
			(stroke
				(width 0.1524)
				(type default)
			)
			(layer "F.SilkS")
		)
		(fp_line
			(start -0.7874 -0.4064)
			(end 0.7874 -0.4064)
			(stroke
				(width 0.1524)
				(type default)
			)
			(layer "F.SilkS")
		)
		(fp_line
			(start 0.7874 -0.4064)
			(end 0.7874 0.4064)
			(stroke
				(width 0.1524)
				(type default)
			)
			(layer "F.SilkS")
		)
		(fp_poly
			(pts
				(xy -0.508 0.2794) (xy -0.508 0.2286) (xy -0.635 0.2286) (xy -0.635 -0.254) (xy -0.5334 -0.254)
				(xy -0.5334 -0.2794) (xy 0.5334 -0.2794) (xy 0.5334 -0.254) (xy 0.635 -0.254) (xy 0.635 0.254) (xy 0.5334 0.254)
				(xy 0.5334 0.2794)
			)
			(stroke
				(width 0)
				(type default)
			)
			(fill no)
			(layer "F.CrtYd")
		)
		(pad "1" smd rect
			(at 0.40005 0 270)
			(size 0.4572 0.508)
			(layers "F.Cu" "F.Mask" "F.Paste")
			(net "BMC_NODE1_CLK_24M_R")
		)
		(pad "2" smd rect
			(at -0.40005 0 270)
			(size 0.4572 0.508)
			(layers "F.Cu" "F.Mask" "F.Paste")
			(net "BMC_NODE1_CLK_24M")
		)
	)
	(footprint ""
		(layer "F.Cu")
		(at 182.412894 -135.89762)
		(property "Reference" "R1047"
			(at 5.246878 0.058674 0)
			(unlocked yes)
			(layer "F.SilkS")
			(effects
				(font
					(size 0.7874 0.5842)
					(thickness 0.1524)
				)
				(justify left)
			)
		)
		(property "Value" ""
			(at 0 0 0)
			(layer "F.Fab")
			(effects
				(font
					(size 1.27 1.27)
				)
			)
		)
		(duplicate_pad_numbers_are_jumpers no)
		(fp_line
			(start -0.7874 -0.4064)
			(end 0.7874 -0.4064)
			(stroke
				(width 0.1524)
				(type default)
			)
			(layer "F.SilkS")
		)
		(fp_line
			(start -0.7874 0.4064)
			(end -0.7874 -0.4064)
			(stroke
				(width 0.1524)
				(type default)
			)
			(layer "F.SilkS")
		)
		(fp_line
			(start 0.7874 -0.4064)
			(end 0.7874 0.4064)
			(stroke
				(width 0.1524)
				(type default)
			)
			(layer "F.SilkS")
		)
		(fp_line
			(start 0.7874 0.4064)
			(end -0.7874 0.4064)
			(stroke
				(width 0.1524)
				(type default)
			)
			(layer "F.SilkS")
		)
		(fp_poly
			(pts
				(xy -0.508 0.2794) (xy -0.508 0.2286) (xy -0.635 0.2286) (xy -0.635 -0.254) (xy -0.5334 -0.254)
				(xy -0.5334 -0.2794) (xy 0.5334 -0.2794) (xy 0.5334 -0.254) (xy 0.635 -0.254) (xy 0.635 0.254) (xy 0.5334 0.254)
				(xy 0.5334 0.2794)
			)
			(stroke
				(width 0)
				(type default)
			)
			(fill no)
			(layer "F.CrtYd")
		)
		(pad "1" smd rect
			(at 0.40005 0)
			(size 0.4572 0.508)
			(layers "F.Cu" "F.Mask" "F.Paste")
			(net "FM_NODE1_DFX_GPIO_GRP05_R")
		)
		(pad "2" smd rect
			(at -0.40005 0)
			(size 0.4572 0.508)
			(layers "F.Cu" "F.Mask" "F.Paste")
			(net "FM_NODE1_DFX_GPIO_GRP05")
		)
	)
	(footprint ""
		(layer "F.Cu")
		(at 16.730472 -70.778878 180)
		(property "Reference" "FS2"
			(at -3.502152 1.438656 0)
			(unlocked yes)
			(layer "F.SilkS")
			(effects
				(font
					(size 0.7874 0.5842)
					(thickness 0.1524)
				)
				(justify left)
			)
		)
		(property "Value" ""
			(at 0 0 180)
			(layer "F.Fab")
			(effects
				(font
					(size 1.27 1.27)
				)
			)
		)
		(duplicate_pad_numbers_are_jumpers no)
		(fp_line
			(start 2.7686 1.8034)
			(end -2.7686 1.8034)
			(stroke
				(width 0.1524)
				(type default)
			)
			(layer "F.SilkS")
		)
		(fp_line
			(start 2.7686 -1.8034)
			(end 2.7686 1.8034)
			(stroke
				(width 0.1524)
				(type default)
			)
			(layer "F.SilkS")
		)
		(fp_line
			(start -2.7686 1.8034)
			(end -2.7686 -1.8034)
			(stroke
				(width 0.1524)
				(type default)
			)
			(layer "F.SilkS")
		)
		(fp_line
			(start -2.7686 -1.8034)
			(end 2.7686 -1.8034)
			(stroke
				(width 0.1524)
				(type default)
			)
			(layer "F.SilkS")
		)
		(fp_poly
			(pts
				(xy -2.6162 1.6764) (xy -2.6162 -1.6764) (xy -1.3716 -1.6764) (xy -1.3716 -1.6002) (xy 1.3716 -1.6002)
				(xy 1.3716 -1.6764) (xy 2.6162 -1.6764) (xy 2.6162 1.6764) (xy 1.3716 1.6764) (xy 1.3716 1.6002)
				(xy -1.3716 1.6002) (xy -1.3716 1.6764)
			)
			(stroke
				(width 0)
				(type default)
			)
			(fill no)
			(layer "F.CrtYd")
		)
		(pad "1" smd rect
			(at -1.999996 0 180)
			(size 1.2192 3.302)
			(layers "F.Cu" "F.Mask" "F.Paste")
			(net "P5V_CRT")
		)
		(pad "2" smd rect
			(at 1.999996 0 180)
			(size 1.2192 3.302)
			(layers "F.Cu" "F.Mask" "F.Paste")
			(net "N21581564")
		)
	)
	(footprint ""
		(layer "F.Cu")
		(at 90.231468 -163.618164)
		(property "Reference" "R801"
			(at 86.577932 70.003416 0)
			(unlocked yes)
			(layer "F.SilkS")
			(effects
				(font
					(size 0.7874 0.5842)
					(thickness 0.1524)
				)
				(justify left)
			)
		)
		(property "Value" ""
			(at 0 0 0)
			(layer "F.Fab")
			(effects
				(font
					(size 1.27 1.27)
				)
			)
		)
		(duplicate_pad_numbers_are_jumpers no)
		(fp_line
			(start -0.7874 -0.4064)
			(end 0.7874 -0.4064)
			(stroke
				(width 0.1524)
				(type default)
			)
			(layer "F.SilkS")
		)
		(fp_line
			(start -0.7874 0.4064)
			(end -0.7874 -0.4064)
			(stroke
				(width 0.1524)
				(type default)
			)
			(layer "F.SilkS")
		)
		(fp_line
			(start 0.7874 -0.4064)
			(end 0.7874 0.4064)
			(stroke
				(width 0.1524)
				(type default)
			)
			(layer "F.SilkS")
		)
		(fp_line
			(start 0.7874 0.4064)
			(end -0.7874 0.4064)
			(stroke
				(width 0.1524)
				(type default)
			)
			(layer "F.SilkS")
		)
		(fp_poly
			(pts
				(xy -0.508 0.2794) (xy -0.508 0.2286) (xy -0.635 0.2286) (xy -0.635 -0.254) (xy -0.5334 -0.254)
				(xy -0.5334 -0.2794) (xy 0.5334 -0.2794) (xy 0.5334 -0.254) (xy 0.635 -0.254) (xy 0.635 0.254) (xy 0.5334 0.254)
				(xy 0.5334 0.2794)
			)
			(stroke
				(width 0)
				(type default)
			)
			(fill no)
			(layer "F.CrtYd")
		)
		(pad "1" smd rect
			(at 0.40005 0)
			(size 0.4572 0.508)
			(layers "F.Cu" "F.Mask" "F.Paste")
			(net "POWER_SW1_PWR_CTR_N")
		)
		(pad "2" smd rect
			(at -0.40005 0)
			(size 0.4572 0.508)
			(layers "F.Cu" "F.Mask" "F.Paste")
			(net "P3V3_STB_NODE1")
		)
	)
	(footprint ""
		(layer "F.Cu")
		(at 133.470396 -130.487166 90)
		(property "Reference" "C189"
			(at -1.572768 2.122678 90)
			(unlocked yes)
			(layer "F.SilkS")
			(effects
				(font
					(size 0.7874 0.5842)
					(thickness 0.1524)
				)
				(justify left)
			)
		)
		(property "Value" ""
			(at 0 0 90)
			(layer "F.Fab")
			(effects
				(font
					(size 1.27 1.27)
				)
			)
		)
		(duplicate_pad_numbers_are_jumpers no)
		(fp_line
			(start 0.7874 -0.4064)
			(end 0.7874 0.4064)
			(stroke
				(width 0.1524)
				(type default)
			)
			(layer "F.SilkS")
		)
		(fp_line
			(start -0.7874 -0.4064)
			(end 0.7874 -0.4064)
			(stroke
				(width 0.1524)
				(type default)
			)
			(layer "F.SilkS")
		)
		(fp_line
			(start 0 0.381)
			(end 0 -0.381)
			(stroke
				(width 0.1524)
				(type default)
			)
			(layer "F.SilkS")
		)
		(fp_line
			(start 0.7874 0.4064)
			(end -0.7874 0.4064)
			(stroke
				(width 0.1524)
				(type default)
			)
			(layer "F.SilkS")
		)
		(fp_line
			(start -0.7874 0.4064)
			(end -0.7874 -0.4064)
			(stroke
				(width 0.1524)
				(type default)
			)
			(layer "F.SilkS")
		)
		(fp_poly
			(pts
				(xy -0.5334 0.254) (xy -0.635 0.254) (xy -0.635 0.2286) (xy -0.635 -0.254) (xy -0.5334 -0.254) (xy -0.5334 -0.2794)
				(xy 0.5334 -0.2794) (xy 0.5334 -0.254) (xy 0.635 -0.254) (xy 0.635 0.254) (xy 0.5334 0.254) (xy 0.5334 0.2794)
				(xy -0.508 0.2794) (xy -0.5334 0.2794)
			)
			(stroke
				(width 0)
				(type default)
			)
			(fill no)
			(layer "F.CrtYd")
		)
		(pad "1" smd rect
			(at 0.40005 0 90)
			(size 0.4572 0.508)
			(layers "F.Cu" "F.Mask" "F.Paste")
			(net "P2E_CPU_USB_NODE1_TX_C_DP")
		)
		(pad "2" smd rect
			(at -0.40005 0 90)
			(size 0.4572 0.508)
			(layers "F.Cu" "F.Mask" "F.Paste")
			(net "P2E_CPU_USB_NODE1_TX_DP")
		)
	)
	(footprint ""
		(layer "F.Cu")
		(at 54.282086 -118.377462)
		(property "Reference" "OSC3"
			(at -6.004814 0.615442 90)
			(unlocked yes)
			(layer "F.SilkS")
			(effects
				(font
					(size 0.7874 0.5842)
					(thickness 0.1524)
				)
				(justify left)
			)
		)
		(property "Value" ""
			(at 0 0 0)
			(layer "F.Fab")
			(effects
				(font
					(size 1.27 1.27)
				)
			)
		)
		(duplicate_pad_numbers_are_jumpers no)
		(fp_line
			(start -1.9558 -1.6002)
			(end 1.9558 -1.6002)
			(stroke
				(width 0.1524)
				(type default)
			)
			(layer "F.SilkS")
		)
		(fp_line
			(start -1.9558 1.6002)
			(end -1.9558 -1.6002)
			(stroke
				(width 0.1524)
				(type default)
			)
			(layer "F.SilkS")
		)
		(fp_line
			(start -1.903984 -0.1016)
			(end -1.524 0)
			(stroke
				(width 0.1524)
				(type default)
			)
			(layer "F.SilkS")
		)
		(fp_line
			(start -1.524 0)
			(end -1.903984 0.1016)
			(stroke
				(width 0.1524)
				(type default)
			)
			(layer "F.SilkS")
		)
		(fp_line
			(start 1.9558 -1.6002)
			(end 1.9558 1.6002)
			(stroke
				(width 0.1524)
				(type default)
			)
			(layer "F.SilkS")
		)
		(fp_line
			(start 1.9558 1.6002)
			(end -1.9558 1.6002)
			(stroke
				(width 0.1524)
				(type default)
			)
			(layer "F.SilkS")
		)
		(fp_poly
			(pts
				(xy -1.0668 1.7145) (xy -1.651 2.8067) (xy -0.5842 2.8067)
			)
			(stroke
				(width 0)
				(type default)
			)
			(fill yes)
			(layer "F.SilkS")
		)
		(fp_poly
			(pts
				(xy -0.3302 1.299972) (xy 0.3302 1.299972) (xy 0.3302 1.524) (xy 1.8796 1.524) (xy 1.8796 0.1778)
				(xy 1.649984 0.1778) (xy 1.649984 -0.1778) (xy 1.8796 -0.1778) (xy 1.8796 -1.524) (xy 0.3302 -1.524)
				(xy 0.3302 -1.299972) (xy -0.3302 -1.299972) (xy -0.3302 -1.524) (xy -1.8796 -1.524) (xy -1.8796 -0.1778)
				(xy -1.649984 -0.1778) (xy -1.649984 0.1778) (xy -1.8796 0.1778) (xy -1.8796 1.524) (xy -0.3302 1.524)
			)
			(stroke
				(width 0)
				(type default)
			)
			(fill no)
			(layer "F.CrtYd")
		)
		(fp_line
			(start -1.649984 -1.299972)
			(end 1.649984 -1.299972)
			(stroke
				(width 0.1)
				(type default)
			)
			(layer "F.Fab")
		)
		(fp_line
			(start -1.649984 1.299972)
			(end -1.649984 -1.299972)
			(stroke
				(width 0.1)
				(type default)
			)
			(layer "F.Fab")
		)
		(fp_line
			(start 1.649984 -1.299972)
			(end 1.649984 1.299972)
			(stroke
				(width 0.1)
				(type default)
			)
			(layer "F.Fab")
		)
		(fp_line
			(start 1.649984 1.299972)
			(end -1.649984 1.299972)
			(stroke
				(width 0.1)
				(type default)
			)
			(layer "F.Fab")
		)
		(fp_text user "1"
			(at -2.608834 1.98247 0)
			(unlocked yes)
			(layer "F.SilkS")
			(effects
				(font
					(size 0.635 0.4064)
					(thickness 0.1524)
				)
				(justify left)
			)
		)
		(fp_text user "4"
			(at -2.51968 -0.016002 0)
			(unlocked yes)
			(layer "F.SilkS")
			(effects
				(font
					(size 0.635 0.4064)
					(thickness 0.1524)
				)
				(justify left)
			)
		)
		(fp_text user "3"
			(at 1.963166 -1.95453 0)
			(unlocked yes)
			(layer "F.SilkS")
			(effects
				(font
					(size 0.635 0.4064)
					(thickness 0.1524)
				)
				(justify left)
			)
		)
		(fp_text user "2"
			(at 2.090166 2.23647 0)
			(unlocked yes)
			(layer "F.SilkS")
			(effects
				(font
					(size 0.635 0.4064)
					(thickness 0.1524)
				)
				(justify left)
			)
		)
		(pad "1" smd rect
			(at -1.100074 0.849884 90)
			(size 1.2192 1.4224)
			(layers "F.Cu" "F.Mask" "F.Paste")
			(net "BMC_NODE1_OSC1_EN")
		)
		(pad "2" smd rect
			(at 1.100074 0.849884 90)
			(size 1.2192 1.4224)
			(layers "F.Cu" "F.Mask" "F.Paste")
			(net "GND")
		)
		(pad "3" smd rect
			(at 1.100074 -0.849884 90)
			(size 1.2192 1.4224)
			(layers "F.Cu" "F.Mask" "F.Paste")
			(net "BMC_NODE1_CLK_24M_R")
		)
		(pad "4" smd rect
			(at -1.100074 -0.849884 90)
			(size 1.2192 1.4224)
			(layers "F.Cu" "F.Mask" "F.Paste")
			(net "BMC_NODE1_OSC1_VDD")
		)
	)
)
